# T6G (Grand Teton) — schematic netlist excerpt (pin names and nets, part order shuffled) for the footprints in the layout excerpt that follows; sources: Cadence DE-HDL packaged netlist, KiCad conversion of 04192023_DAF0TMB3IC0_F0TG_MB_C_brd_V02_OCP.brd

C2471  Q_CAP  22UF 4V 20% X6S  pkg C0402  page 74 : A = PVDDCR_SOC_P1 ; B = GND
R681  Q_RES  49.9 1% CHIP  pkg 0201LF  page 298 : A = SMB_RT_CPU0_P2_ROM_MUX_1D_SDA ; B = SMB_RT_CPU0_P2_ROM_MUX_1D_R_SDA
R1245  Q_RES  0 5% EMPTY  pkg 0402LF  page 258 : A = P1V2_AUX_ADC ; B = P1V2_AUX_ADC_MAM

(kicad_pcb
	(version 20260206)
	(generator "pcbnew")
	(generator_version "10.0")
	(general
		(thickness 1.6)
		(legacy_teardrops no)
	)
	(paper "A4")
	(title_block
		(title "04192023_DAF0TMB3IC0_F0TG_MB_C_brd_V02_OCP.brd")
		(comment 1 "Grand Teton / footprints 7147-7149 of 8354")
	)
	(layers
		(0 "F.Cu" signal "TOP")
		(4 "In1.Cu" signal "GND")
		(6 "In2.Cu" signal "IN1")
		(8 "In3.Cu" signal "GND1")
		(10 "In4.Cu" signal "IN2")
		(12 "In5.Cu" signal "GND2")
		(14 "In6.Cu" signal "IN3")
		(16 "In7.Cu" signal "GND3")
		(18 "In8.Cu" signal "VCC")
		(20 "In9.Cu" signal "VCC1")
		(22 "In10.Cu" signal "GND4")
		(24 "In11.Cu" signal "IN4")
		(26 "In12.Cu" signal "GND5")
		(28 "In13.Cu" signal "IN5")
		(30 "In14.Cu" signal "GND6")
		(32 "In15.Cu" signal "IN6")
		(34 "In16.Cu" signal "GND7")
		(2 "B.Cu" signal "BOTTOM")
		(9 "F.Adhes" user "F.Adhesive")
		(11 "B.Adhes" user "B.Adhesive")
		(13 "F.Paste" user "Package Geometry/Pastemask Top")
		(15 "B.Paste" user "Package Geometry/Pastemask Bottom")
		(5 "F.SilkS" user "Ref Des/Silkscreen Top")
		(7 "B.SilkS" user "Ref Des/Silkscreen Bottom")
		(1 "F.Mask" user "Board Geometry/Soldermask Top")
		(3 "B.Mask" user "Board Geometry/Soldermask Bottom")
		(17 "Dwgs.User" user "User.Drawings")
		(19 "Cmts.User" user "User.Comments")
		(21 "Eco1.User" user "User.Eco1")
		(23 "Eco2.User" user "User.Eco2")
		(25 "Edge.Cuts" user "Board Geometry/Outline")
		(27 "Margin" user)
		(31 "F.CrtYd" user "Package Geometry/Place Bound Top")
		(29 "B.CrtYd" user "Package Geometry/Place Bound Bottom")
		(35 "F.Fab" user "Ref Des/Assembly Top")
		(33 "B.Fab" user "Ref Des/Assembly Bottom")
	)
	(footprint ""
		(layer "B.Cu")
		(at 125.389386 -252.543564)
		(property "Reference" "C2471"
			(at 0 0 0)
			(layer "B.SilkS")
			(hide yes)
			(effects
				(font
					(size 1.27 1.27)
				)
				(justify mirror)
			)
		)
		(property "Value" ""
			(at 0 0 0)
			(layer "B.Fab")
			(effects
				(font
					(size 1.27 1.27)
				)
				(justify mirror)
			)
		)
		(duplicate_pad_numbers_are_jumpers no)
		(fp_line
			(start -0.7874 -0.4064)
			(end -0.7874 0.4064)
			(stroke
				(width 0.1524)
				(type default)
			)
			(layer "B.SilkS")
		)
		(fp_line
			(start -0.7874 0.4064)
			(end 0.7874 0.4064)
			(stroke
				(width 0.1524)
				(type default)
			)
			(layer "B.SilkS")
		)
		(fp_line
			(start 0.7874 -0.4064)
			(end -0.7874 -0.4064)
			(stroke
				(width 0.1524)
				(type default)
			)
			(layer "B.SilkS")
		)
		(fp_line
			(start 0.7874 0.4064)
			(end 0.7874 -0.4064)
			(stroke
				(width 0.1524)
				(type default)
			)
			(layer "B.SilkS")
		)
		(fp_line
			(start -0.67945 -0.3048)
			(end -0.67945 0.3048)
			(stroke
				(width 0.1)
				(type default)
			)
			(layer "B.Fab")
		)
		(fp_line
			(start -0.67945 0.3048)
			(end -0.120396 0.3048)
			(stroke
				(width 0.1)
				(type default)
			)
			(layer "B.Fab")
		)
		(fp_line
			(start -0.12065 -0.3048)
			(end -0.67945 -0.3048)
			(stroke
				(width 0.1)
				(type default)
			)
			(layer "B.Fab")
		)
		(fp_line
			(start -0.12065 -0.2794)
			(end -0.12065 -0.3048)
			(stroke
				(width 0.1)
				(type default)
			)
			(layer "B.Fab")
		)
		(fp_line
			(start -0.120396 0.2794)
			(end 0.12065 0.2794)
			(stroke
				(width 0.1)
				(type default)
			)
			(layer "B.Fab")
		)
		(fp_line
			(start -0.120396 0.3048)
			(end -0.120396 0.2794)
			(stroke
				(width 0.1)
				(type default)
			)
			(layer "B.Fab")
		)
		(fp_line
			(start 0.12065 -0.305054)
			(end 0.12065 -0.2794)
			(stroke
				(width 0.1)
				(type default)
			)
			(layer "B.Fab")
		)
		(fp_line
			(start 0.12065 -0.2794)
			(end -0.12065 -0.2794)
			(stroke
				(width 0.1)
				(type default)
			)
			(layer "B.Fab")
		)
		(fp_line
			(start 0.12065 0.2794)
			(end 0.12065 0.3048)
			(stroke
				(width 0.1)
				(type default)
			)
			(layer "B.Fab")
		)
		(fp_line
			(start 0.12065 0.3048)
			(end 0.67945 0.3048)
			(stroke
				(width 0.1)
				(type default)
			)
			(layer "B.Fab")
		)
		(fp_line
			(start 0.67945 -0.305054)
			(end 0.12065 -0.305054)
			(stroke
				(width 0.1)
				(type default)
			)
			(layer "B.Fab")
		)
		(fp_line
			(start 0.67945 0.3048)
			(end 0.67945 -0.305054)
			(stroke
				(width 0.1)
				(type default)
			)
			(layer "B.Fab")
		)
		(pad "1" smd circle
			(at 0.40005 0 180)
			(size 0 0)
			(layers "B.Cu" "B.Mask" "B.Paste")
			(net "PVDDCR_SOC_P1")
		)
		(pad "2" smd circle
			(at -0.40005 0 180)
			(size 0 0)
			(layers "B.Cu" "B.Mask" "B.Paste")
			(net "GND")
		)
	)
	(footprint ""
		(layer "B.Cu")
		(at 421.95877 -422.28897)
		(property "Reference" "R681"
			(at 0 0 0)
			(layer "B.SilkS")
			(hide yes)
			(effects
				(font
					(size 1.27 1.27)
				)
				(justify mirror)
			)
		)
		(property "Value" ""
			(at 0 0 0)
			(layer "B.Fab")
			(effects
				(font
					(size 1.27 1.27)
				)
				(justify mirror)
			)
		)
		(duplicate_pad_numbers_are_jumpers no)
		(fp_line
			(start -0.32512 -0.175006)
			(end -0.32512 0.175006)
			(stroke
				(width 0.1)
				(type default)
			)
			(layer "B.Fab")
		)
		(fp_line
			(start -0.32512 0.175006)
			(end 0.32512 0.175006)
			(stroke
				(width 0.1)
				(type default)
			)
			(layer "B.Fab")
		)
		(fp_line
			(start 0.32512 -0.175006)
			(end -0.32512 -0.175006)
			(stroke
				(width 0.1)
				(type default)
			)
			(layer "B.Fab")
		)
		(fp_line
			(start 0.32512 0.175006)
			(end 0.32512 -0.175006)
			(stroke
				(width 0.1)
				(type default)
			)
			(layer "B.Fab")
		)
		(pad "1" smd rect
			(at 0.2667 0 180)
			(size 0.3048 0.381)
			(layers "B.Cu" "B.Mask" "B.Paste")
			(net "SMB_RT_CPU0_P2_ROM_MUX_1D_SDA")
		)
		(pad "2" smd rect
			(at -0.2667 0)
			(size 0.3048 0.381)
			(layers "B.Cu" "B.Mask" "B.Paste")
			(net "SMB_RT_CPU0_P2_ROM_MUX_1D_R_SDA")
		)
	)
	(footprint ""
		(layer "B.Cu")
		(at 231.874822 -323.913754 180)
		(property "Reference" "R1245"
			(at 0 0 0)
			(layer "B.SilkS")
			(hide yes)
			(effects
				(font
					(size 1.27 1.27)
				)
				(justify mirror)
			)
		)
		(property "Value" ""
			(at 0 0 0)
			(layer "B.Fab")
			(effects
				(font
					(size 1.27 1.27)
				)
				(justify mirror)
			)
		)
		(duplicate_pad_numbers_are_jumpers no)
		(fp_line
			(start 0.7874 0.4064)
			(end 0.7874 -0.4064)
			(stroke
				(width 0.1524)
				(type default)
			)
			(layer "B.SilkS")
		)
		(fp_line
			(start 0.7874 -0.4064)
			(end -0.7874 -0.4064)
			(stroke
				(width 0.1524)
				(type default)
			)
			(layer "B.SilkS")
		)
		(fp_line
			(start -0.7874 0.4064)
			(end 0.7874 0.4064)
			(stroke
				(width 0.1524)
				(type default)
			)
			(layer "B.SilkS")
		)
		(fp_line
			(start -0.7874 -0.4064)
			(end -0.7874 0.4064)
			(stroke
				(width 0.1524)
				(type default)
			)
			(layer "B.SilkS")
		)
		(fp_line
			(start 0.67945 0.3048)
			(end 0.67945 -0.305054)
			(stroke
				(width 0.1)
				(type default)
			)
			(layer "B.Fab")
		)
		(fp_line
			(start 0.67945 -0.305054)
			(end 0.12065 -0.305054)
			(stroke
				(width 0.1)
				(type default)
			)
			(layer "B.Fab")
		)
		(fp_line
			(start 0.12065 0.3048)
			(end 0.67945 0.3048)
			(stroke
				(width 0.1)
				(type default)
			)
			(layer "B.Fab")
		)
		(fp_line
			(start 0.12065 0.2794)
			(end 0.12065 0.3048)
			(stroke
				(width 0.1)
				(type default)
			)
			(layer "B.Fab")
		)
		(fp_line
			(start 0.12065 -0.2794)
			(end -0.12065 -0.2794)
			(stroke
				(width 0.1)
				(type default)
			)
			(layer "B.Fab")
		)
		(fp_line
			(start 0.12065 -0.305054)
			(end 0.12065 -0.2794)
			(stroke
				(width 0.1)
				(type default)
			)
			(layer "B.Fab")
		)
		(fp_line
			(start -0.120396 0.3048)
			(end -0.120396 0.2794)
			(stroke
				(width 0.1)
				(type default)
			)
			(layer "B.Fab")
		)
		(fp_line
			(start -0.120396 0.2794)
			(end 0.12065 0.2794)
			(stroke
				(width 0.1)
				(type default)
			)
			(layer "B.Fab")
		)
		(fp_line
			(start -0.12065 -0.2794)
			(end -0.12065 -0.3048)
			(stroke
				(width 0.1)
				(type default)
			)
			(layer "B.Fab")
		)
		(fp_line
			(start -0.12065 -0.3048)
			(end -0.67945 -0.3048)
			(stroke
				(width 0.1)
				(type default)
			)
			(layer "B.Fab")
		)
		(fp_line
			(start -0.67945 0.3048)
			(end -0.120396 0.3048)
			(stroke
				(width 0.1)
				(type default)
			)
			(layer "B.Fab")
		)
		(fp_line
			(start -0.67945 -0.3048)
			(end -0.67945 0.3048)
			(stroke
				(width 0.1)
				(type default)
			)
			(layer "B.Fab")
		)
		(pad "1" smd rect
			(at 0.40005 0 180)
			(size 0.4572 0.508)
			(layers "B.Cu" "B.Mask" "B.Paste")
			(net "P1V2_AUX_ADC")
		)
		(pad "2" smd rect
			(at -0.40005 0 180)
			(size 0.4572 0.508)
			(layers "B.Cu" "B.Mask" "B.Paste")
			(net "P1V2_AUX_ADC_MAM")
		)
	)
)
